(kicad_pcb
	(version 20211014)
	(generator pcbnew)
	(general
    (thickness 1.6)
  )
	(paper "A4")
	(title_block
    (title "SA800U (Snapdragon 845) Baseboard")
    (date "2023-10-19")
    (rev "1.0.3")
    (company "Antmicro Ltd.")
    (comment 1 "www.antmicro.com")
		(comment 9 "footprints 273-282 of 589")
	)
	(layers
    (0 "F.Cu" signal)
    (1 "In1.Cu" power)
    (2 "In2.Cu" signal)
    (3 "In3.Cu" signal)
    (4 "In4.Cu" power)
    (31 "B.Cu" signal)
    (32 "B.Adhes" user "B.Adhesive")
    (33 "F.Adhes" user "F.Adhesive")
    (34 "B.Paste" user)
    (35 "F.Paste" user)
    (36 "B.SilkS" user "B.Silkscreen")
    (37 "F.SilkS" user "F.Silkscreen")
    (38 "B.Mask" user)
    (39 "F.Mask" user)
    (40 "Dwgs.User" user "User.Drawings")
    (41 "Cmts.User" user "User.Comments")
    (42 "Eco1.User" user "User.Eco1")
    (43 "Eco2.User" user "User.Eco2")
    (44 "Edge.Cuts" user)
    (45 "Margin" user)
    (46 "B.CrtYd" user "B.Courtyard")
    (47 "F.CrtYd" user "F.Courtyard")
    (48 "B.Fab" user)
    (49 "F.Fab" user)
  )
	(footprint "sa800u-baseboard-hw-footprints:R_0402_1005Metric" (layer "B.Cu")
    (tedit 5FD9C158)
    (at 116.9 116.2 90)
    (descr "Resistor SMD 0402")
    (tags "resistor SMD 0402")
    (property "Author" "Antmicro")
    (property "License" "Apache-2.0")
    (property "MPN" "CR0402-FX-4701GLF")
    (property "Manufacturer" "Bourns")
    (property "Sheetfile" "hdmi-converter.kicad_sch")
    (property "Sheetname" "HDMI converter")
    (property "Tolerance" "1%")
    (property "Val" "4k7")
    (attr smd)
    (fp_text reference "R24" (at 1.15 -0.58 270) (layer "B.SilkS")
      (effects (font (size 0.7 0.7) (thickness 0.15)) (justify left bottom mirror))
    )
    (fp_text value "R_4k7_0402" (at 0 -1.4 270) (layer "B.Fab")
      (effects (font (size 0.7 0.7) (thickness 0.15)) (justify left bottom mirror))
    )
    (fp_text user "License: Apache-2.0" (at -0.95 -5.169 270) (layer "B.Fab") hide
      (effects (font (size 0.7 0.7) (thickness 0.15)) (justify left bottom mirror))
    )
    (fp_text user "${REFERENCE}" (at -0.95 -3.168 270) (layer "B.Fab") hide
      (effects (font (size 0.7 0.7) (thickness 0.15)) (justify left bottom mirror))
    )
    (fp_text user "Author: Antmicro" (at -0.95 -4.169 270) (layer "B.Fab") hide
      (effects (font (size 0.7 0.7) (thickness 0.15)) (justify left bottom mirror))
    )
    (fp_rect (start -0.93 0.47) (end 0.93 -0.47) (layer "B.CrtYd") (width 0.05) (fill none))
    (fp_rect (start -0.5 0.25) (end 0.5 -0.25) (layer "B.Fab") (width 0.15) (fill none))
    (pad "1" smd roundrect (at -0.485 0 90) (size 0.59 0.64) (layers "B.Cu" "B.Paste" "B.Mask") (roundrect_rratio 0.25)
      (net 132 "VREG_S4A_1V8") (pintype "passive"))
    (pad "2" smd roundrect (at 0.485 0 90) (size 0.59 0.64) (layers "B.Cu" "B.Paste" "B.Mask") (roundrect_rratio 0.25)
      (net 36 "LT9611_RST") (pintype "passive"))
  )
	(footprint "sa800u-baseboard-hw-footprints:R_0402_1005Metric" (layer "B.Cu")
    (tedit 5FD9C158)
    (at 120.8 113.9 90)
    (descr "Resistor SMD 0402")
    (tags "resistor SMD 0402")
    (property "Author" "Antmicro")
    (property "License" "Apache-2.0")
    (property "MPN" "CR0402-FX-4701GLF")
    (property "Manufacturer" "Bourns")
    (property "Sheetfile" "hdmi-converter.kicad_sch")
    (property "Sheetname" "HDMI converter")
    (property "Tolerance" "1%")
    (property "Val" "4k7")
    (attr smd)
    (fp_text reference "R25" (at 1.19 1.37 270) (layer "B.SilkS")
      (effects (font (size 0.7 0.7) (thickness 0.15)) (justify left bottom mirror))
    )
    (fp_text value "R_4k7_0402" (at 0 -1.4 270) (layer "B.Fab")
      (effects (font (size 0.7 0.7) (thickness 0.15)) (justify left bottom mirror))
    )
    (fp_text user "License: Apache-2.0" (at -0.95 -5.169 270) (layer "B.Fab") hide
      (effects (font (size 0.7 0.7) (thickness 0.15)) (justify left bottom mirror))
    )
    (fp_text user "${REFERENCE}" (at -0.95 -3.168 270) (layer "B.Fab") hide
      (effects (font (size 0.7 0.7) (thickness 0.15)) (justify left bottom mirror))
    )
    (fp_text user "Author: Antmicro" (at -0.95 -4.169 270) (layer "B.Fab") hide
      (effects (font (size 0.7 0.7) (thickness 0.15)) (justify left bottom mirror))
    )
    (fp_rect (start -0.93 0.47) (end 0.93 -0.47) (layer "B.CrtYd") (width 0.05) (fill none))
    (fp_rect (start -0.5 0.25) (end 0.5 -0.25) (layer "B.Fab") (width 0.15) (fill none))
    (pad "1" smd roundrect (at -0.485 0 90) (size 0.59 0.64) (layers "B.Cu" "B.Paste" "B.Mask") (roundrect_rratio 0.25)
      (net 131 "3V3_SYS") (pintype "passive"))
    (pad "2" smd roundrect (at 0.485 0 90) (size 0.59 0.64) (layers "B.Cu" "B.Paste" "B.Mask") (roundrect_rratio 0.25)
      (net 284 "/HDMI converter/LT9611_INTO_GPIO5") (pintype "passive"))
  )
	(footprint "sa800u-baseboard-hw-footprints:R_0402_1005Metric" (layer "B.Cu")
    (tedit 5FD9C158)
    (at 120.8 115.9 -90)
    (descr "Resistor SMD 0402")
    (tags "resistor SMD 0402")
    (property "Author" "Antmicro")
    (property "License" "Apache-2.0")
    (property "MPN" "CR0402-FX-4701GLF")
    (property "Manufacturer" "Bourns")
    (property "Sheetfile" "hdmi-converter.kicad_sch")
    (property "Sheetname" "HDMI converter")
    (property "Tolerance" "1%")
    (property "Val" "4k7")
    (attr smd)
    (fp_text reference "R26" (at -1.22 -2.38 90) (layer "B.SilkS")
      (effects (font (size 0.7 0.7) (thickness 0.15)) (justify left bottom mirror))
    )
    (fp_text value "R_4k7_0402" (at 0 -1.4 90) (layer "B.Fab")
      (effects (font (size 0.7 0.7) (thickness 0.15)) (justify left bottom mirror))
    )
    (fp_text user "Author: Antmicro" (at -0.95 -4.169 90) (layer "B.Fab") hide
      (effects (font (size 0.7 0.7) (thickness 0.15)) (justify left bottom mirror))
    )
    (fp_text user "License: Apache-2.0" (at -0.95 -5.169 90) (layer "B.Fab") hide
      (effects (font (size 0.7 0.7) (thickness 0.15)) (justify left bottom mirror))
    )
    (fp_text user "${REFERENCE}" (at -0.95 -3.168 90) (layer "B.Fab") hide
      (effects (font (size 0.7 0.7) (thickness 0.15)) (justify left bottom mirror))
    )
    (fp_rect (start -0.93 0.47) (end 0.93 -0.47) (layer "B.CrtYd") (width 0.05) (fill none))
    (fp_rect (start -0.5 0.25) (end 0.5 -0.25) (layer "B.Fab") (width 0.15) (fill none))
    (pad "1" smd roundrect (at -0.485 0 270) (size 0.59 0.64) (layers "B.Cu" "B.Paste" "B.Mask") (roundrect_rratio 0.25)
      (net 131 "3V3_SYS") (pintype "passive"))
    (pad "2" smd roundrect (at 0.485 0 270) (size 0.59 0.64) (layers "B.Cu" "B.Paste" "B.Mask") (roundrect_rratio 0.25)
      (net 186 "/HDMI converter/LT9611_RST_N") (pintype "passive"))
  )
	(footprint "sa800u-baseboard-hw-footprints:R_0402_1005Metric" (layer "B.Cu")
    (tedit 5FD9C158)
    (at 59.6 113.8 180)
    (descr "Resistor SMD 0402")
    (tags "resistor SMD 0402")
    (property "Author" "Antmicro")
    (property "License" "Apache-2.0")
    (property "MPN" "CR0402-FX-63R4GLF")
    (property "Manufacturer" "Bourns")
    (property "Sheetfile" "poe.kicad_sch")
    (property "Sheetname" "PoE")
    (property "Tolerance" "1%")
    (property "Val" "63R4")
    (attr smd)
    (fp_text reference "R144" (at 0.91 -0.37) (layer "B.SilkS")
      (effects (font (size 0.7 0.7) (thickness 0.15)) (justify left bottom mirror))
    )
    (fp_text value "R_63R4_0402" (at 0 -1.4) (layer "B.Fab")
      (effects (font (size 0.7 0.7) (thickness 0.15)) (justify left bottom mirror))
    )
    (fp_text user "License: Apache-2.0" (at -0.95 -5.169) (layer "B.Fab") hide
      (effects (font (size 0.7 0.7) (thickness 0.15)) (justify left bottom mirror))
    )
    (fp_text user "Author: Antmicro" (at -0.95 -4.169) (layer "B.Fab") hide
      (effects (font (size 0.7 0.7) (thickness 0.15)) (justify left bottom mirror))
    )
    (fp_text user "${REFERENCE}" (at -0.95 -3.168) (layer "B.Fab") hide
      (effects (font (size 0.7 0.7) (thickness 0.15)) (justify left bottom mirror))
    )
    (fp_rect (start -0.93 0.47) (end 0.93 -0.47) (layer "B.CrtYd") (width 0.05) (fill none))
    (fp_rect (start -0.5 0.25) (end 0.5 -0.25) (layer "B.Fab") (width 0.15) (fill none))
    (pad "1" smd roundrect (at -0.485 0 180) (size 0.59 0.64) (layers "B.Cu" "B.Paste" "B.Mask") (roundrect_rratio 0.25)
      (net 146 "/PoE/CLS") (pintype "passive"))
    (pad "2" smd roundrect (at 0.485 0 180) (size 0.59 0.64) (layers "B.Cu" "B.Paste" "B.Mask") (roundrect_rratio 0.25)
      (net 135 "/PoE/VSS_POE") (pintype "passive"))
  )
	(footprint "sa800u-baseboard-hw-footprints:R_0402_1005Metric" (layer "B.Cu")
    (tedit 5FD9C158)
    (at 75.6 96.1 -90)
    (descr "Resistor SMD 0402")
    (tags "resistor SMD 0402")
    (property "Author" "Antmicro")
    (property "Current" "1A")
    (property "DNP" "DNP")
    (property "License" "Apache-2.0")
    (property "MPN" "ERJ2GE0R00X")
    (property "Manufacturer" "Panasonic")
    (property "Sheetfile" "poe.kicad_sch")
    (property "Sheetname" "PoE")
    (property "Tolerance" "")
    (property "Val" "0R")
    (attr exclude_from_pos_files)
    (fp_text reference "R151" (at -1.27 0.57 90) (layer "B.SilkS")
      (effects (font (size 0.7 0.7) (thickness 0.15)) (justify left bottom mirror))
    )
    (fp_text value "R_0R_0402" (at 0 -1.4 90) (layer "B.Fab")
      (effects (font (size 0.7 0.7) (thickness 0.15)) (justify left bottom mirror))
    )
    (fp_text user "License: Apache-2.0" (at -0.95 -5.169 90) (layer "B.Fab") hide
      (effects (font (size 0.7 0.7) (thickness 0.15)) (justify left bottom mirror))
    )
    (fp_text user "Author: Antmicro" (at -0.95 -4.169 90) (layer "B.Fab") hide
      (effects (font (size 0.7 0.7) (thickness 0.15)) (justify left bottom mirror))
    )
    (fp_text user "${REFERENCE}" (at -0.95 -3.168 90) (layer "B.Fab") hide
      (effects (font (size 0.7 0.7) (thickness 0.15)) (justify left bottom mirror))
    )
    (fp_rect (start -0.93 0.47) (end 0.93 -0.47) (layer "B.CrtYd") (width 0.05) (fill none))
    (fp_rect (start -0.5 0.25) (end 0.5 -0.25) (layer "B.Fab") (width 0.15) (fill none))
    (pad "1" smd roundrect (at -0.485 0 270) (size 0.59 0.64) (layers "B.Cu" "B.Paste" "B.Mask") (roundrect_rratio 0.25)
      (net 153 "/PoE/TRIM") (pintype "passive"))
    (pad "2" smd roundrect (at 0.485 0 270) (size 0.59 0.64) (layers "B.Cu" "B.Paste" "B.Mask") (roundrect_rratio 0.25)
      (net 136 "5V_POE") (pintype "passive"))
  )
	(footprint "sa800u-baseboard-hw-footprints:R_0402_1005Metric" (layer "B.Cu")
    (tedit 5FD9C158)
    (at 75.6 94.1 90)
    (descr "Resistor SMD 0402")
    (tags "resistor SMD 0402")
    (property "Author" "Antmicro")
    (property "Current" "1A")
    (property "DNP" "DNP")
    (property "License" "Apache-2.0")
    (property "MPN" "ERJ2GE0R00X")
    (property "Manufacturer" "Panasonic")
    (property "Sheetfile" "poe.kicad_sch")
    (property "Sheetname" "PoE")
    (property "Tolerance" "")
    (property "Val" "0R")
    (attr exclude_from_pos_files)
    (fp_text reference "R152" (at 2 -0.57 270) (layer "B.SilkS")
      (effects (font (size 0.7 0.7) (thickness 0.15)) (justify left bottom mirror))
    )
    (fp_text value "R_0R_0402" (at 0 -1.4 270) (layer "B.Fab")
      (effects (font (size 0.7 0.7) (thickness 0.15)) (justify left bottom mirror))
    )
    (fp_text user "${REFERENCE}" (at -0.95 -3.168 270) (layer "B.Fab") hide
      (effects (font (size 0.7 0.7) (thickness 0.15)) (justify left bottom mirror))
    )
    (fp_text user "License: Apache-2.0" (at -0.95 -5.169 270) (layer "B.Fab") hide
      (effects (font (size 0.7 0.7) (thickness 0.15)) (justify left bottom mirror))
    )
    (fp_text user "Author: Antmicro" (at -0.95 -4.169 270) (layer "B.Fab") hide
      (effects (font (size 0.7 0.7) (thickness 0.15)) (justify left bottom mirror))
    )
    (fp_rect (start -0.93 0.47) (end 0.93 -0.47) (layer "B.CrtYd") (width 0.05) (fill none))
    (fp_rect (start -0.5 0.25) (end 0.5 -0.25) (layer "B.Fab") (width 0.15) (fill none))
    (pad "1" smd roundrect (at -0.485 0 90) (size 0.59 0.64) (layers "B.Cu" "B.Paste" "B.Mask") (roundrect_rratio 0.25)
      (net 153 "/PoE/TRIM") (pintype "passive"))
    (pad "2" smd roundrect (at 0.485 0 90) (size 0.59 0.64) (layers "B.Cu" "B.Paste" "B.Mask") (roundrect_rratio 0.25)
      (net 1 "GND") (pintype "passive"))
  )
	(footprint "sa800u-baseboard-hw-footprints:R_0402_1005Metric" (layer "B.Cu")
    (tedit 5FD9C158)
    (at 60.1 104.7 90)
    (descr "Resistor SMD 0402")
    (tags "resistor SMD 0402")
    (property "Author" "Antmicro")
    (property "Current" "1A")
    (property "License" "Apache-2.0")
    (property "MPN" "ERJ2GE0R00X")
    (property "Manufacturer" "Panasonic")
    (property "Sheetfile" "poe.kicad_sch")
    (property "Sheetname" "PoE")
    (property "Tolerance" "")
    (property "Val" "0R")
    (attr smd)
    (fp_text reference "R146" (at 1.38 -0.48 270) (layer "B.SilkS")
      (effects (font (size 0.7 0.7) (thickness 0.15)) (justify left bottom mirror))
    )
    (fp_text value "R_0R_0402" (at 0 -1.4 270) (layer "B.Fab")
      (effects (font (size 0.7 0.7) (thickness 0.15)) (justify left bottom mirror))
    )
    (fp_text user "Author: Antmicro" (at -0.95 -4.169 270) (layer "B.Fab") hide
      (effects (font (size 0.7 0.7) (thickness 0.15)) (justify left bottom mirror))
    )
    (fp_text user "${REFERENCE}" (at -0.95 -3.168 270) (layer "B.Fab") hide
      (effects (font (size 0.7 0.7) (thickness 0.15)) (justify left bottom mirror))
    )
    (fp_text user "License: Apache-2.0" (at -0.95 -5.169 270) (layer "B.Fab") hide
      (effects (font (size 0.7 0.7) (thickness 0.15)) (justify left bottom mirror))
    )
    (fp_rect (start -0.93 0.47) (end 0.93 -0.47) (layer "B.CrtYd") (width 0.05) (fill none))
    (fp_rect (start -0.5 0.25) (end 0.5 -0.25) (layer "B.Fab") (width 0.15) (fill none))
    (pad "1" smd roundrect (at -0.485 0 90) (size 0.59 0.64) (layers "B.Cu" "B.Paste" "B.Mask") (roundrect_rratio 0.25)
      (net 147 "/PoE/CDB") (pintype "passive"))
    (pad "2" smd roundrect (at 0.485 0 90) (size 0.59 0.64) (layers "B.Cu" "B.Paste" "B.Mask") (roundrect_rratio 0.25)
      (net 76 "/PoE/SMPS_CTRL") (pintype "passive"))
  )
	(footprint "sa800u-baseboard-hw-footprints:R_0402_1005Metric" (layer "B.Cu")
    (tedit 5FD9C158)
    (at 59.4 103.11)
    (descr "Resistor SMD 0402")
    (tags "resistor SMD 0402")
    (property "Author" "Antmicro")
    (property "DNP" "DNP")
    (property "License" "Apache-2.0")
    (property "MPN" "CR0402-FX-1003GLF")
    (property "Manufacturer" "Bourns")
    (property "Sheetfile" "poe.kicad_sch")
    (property "Sheetname" "PoE")
    (property "Tolerance" "1%")
    (property "Val" "100k")
    (attr exclude_from_pos_files)
    (fp_text reference "R147" (at 1.04 -0.51 180) (layer "B.SilkS")
      (effects (font (size 0.7 0.7) (thickness 0.15)) (justify left bottom mirror))
    )
    (fp_text value "R_100k_0402" (at 0 -1.4 180) (layer "B.Fab")
      (effects (font (size 0.7 0.7) (thickness 0.15)) (justify left bottom mirror))
    )
    (fp_text user "License: Apache-2.0" (at -0.95 -5.169 180) (layer "B.Fab") hide
      (effects (font (size 0.7 0.7) (thickness 0.15)) (justify left bottom mirror))
    )
    (fp_text user "Author: Antmicro" (at -0.95 -4.169 180) (layer "B.Fab") hide
      (effects (font (size 0.7 0.7) (thickness 0.15)) (justify left bottom mirror))
    )
    (fp_text user "${REFERENCE}" (at -0.95 -3.168 180) (layer "B.Fab") hide
      (effects (font (size 0.7 0.7) (thickness 0.15)) (justify left bottom mirror))
    )
    (fp_rect (start -0.93 0.47) (end 0.93 -0.47) (layer "B.CrtYd") (width 0.05) (fill none))
    (fp_rect (start -0.5 0.25) (end 0.5 -0.25) (layer "B.Fab") (width 0.15) (fill none))
    (pad "1" smd roundrect (at -0.485 0) (size 0.59 0.64) (layers "B.Cu" "B.Paste" "B.Mask") (roundrect_rratio 0.25)
      (net 73 "/PoE/VDD_POE") (pintype "passive"))
    (pad "2" smd roundrect (at 0.485 0) (size 0.59 0.64) (layers "B.Cu" "B.Paste" "B.Mask") (roundrect_rratio 0.25)
      (net 76 "/PoE/SMPS_CTRL") (pintype "passive"))
  )
	(footprint "sa800u-baseboard-hw-footprints:R_0402_1005Metric" (layer "B.Cu")
    (tedit 5FD9C158)
    (at 61.4 103.11)
    (descr "Resistor SMD 0402")
    (tags "resistor SMD 0402")
    (property "Author" "Antmicro")
    (property "DNP" "DNP")
    (property "License" "Apache-2.0")
    (property "MPN" "CR0402-FX-1003GLF")
    (property "Manufacturer" "Bourns")
    (property "Sheetfile" "poe.kicad_sch")
    (property "Sheetname" "PoE")
    (property "Tolerance" "1%")
    (property "Val" "100k")
    (attr exclude_from_pos_files)
    (fp_text reference "R148" (at 1.76 -0.46 180) (layer "B.SilkS")
      (effects (font (size 0.7 0.7) (thickness 0.15)) (justify left bottom mirror))
    )
    (fp_text value "R_100k_0402" (at 0 -1.4 180) (layer "B.Fab")
      (effects (font (size 0.7 0.7) (thickness 0.15)) (justify left bottom mirror))
    )
    (fp_text user "Author: Antmicro" (at -0.95 -4.169 180) (layer "B.Fab") hide
      (effects (font (size 0.7 0.7) (thickness 0.15)) (justify left bottom mirror))
    )
    (fp_text user "${REFERENCE}" (at -0.95 -3.168 180) (layer "B.Fab") hide
      (effects (font (size 0.7 0.7) (thickness 0.15)) (justify left bottom mirror))
    )
    (fp_text user "License: Apache-2.0" (at -0.95 -5.169 180) (layer "B.Fab") hide
      (effects (font (size 0.7 0.7) (thickness 0.15)) (justify left bottom mirror))
    )
    (fp_rect (start -0.93 0.47) (end 0.93 -0.47) (layer "B.CrtYd") (width 0.05) (fill none))
    (fp_rect (start -0.5 0.25) (end 0.5 -0.25) (layer "B.Fab") (width 0.15) (fill none))
    (pad "1" smd roundrect (at -0.485 0) (size 0.59 0.64) (layers "B.Cu" "B.Paste" "B.Mask") (roundrect_rratio 0.25)
      (net 76 "/PoE/SMPS_CTRL") (pintype "passive"))
    (pad "2" smd roundrect (at 0.485 0) (size 0.59 0.64) (layers "B.Cu" "B.Paste" "B.Mask") (roundrect_rratio 0.25)
      (net 7 "GNDD") (pintype "passive"))
  )
	(footprint "sa800u-baseboard-hw-footprints:FB_0805_2012Metric" (layer "B.Cu")
    (tedit 5D5D3F54)
    (at 58.25 119.5 90)
    (property "Author" "Antmicro")
    (property "License" "Apache-2.0")
    (property "MPN" "BLM21PG221SN1D")
    (property "Manufacturer" "Murata")
    (property "Sheetfile" "poe.kicad_sch")
    (property "Sheetname" "PoE")
    (attr smd)
    (fp_text reference "FB5" (at 1.02 -0.94 270) (layer "B.SilkS")
      (effects (font (size 0.7 0.7) (thickness 0.15)) (justify left bottom mirror))
    )
    (fp_text value "FB_220Z_2A_0805" (at 0 -1.8 270) (layer "B.Fab")
      (effects (font (size 0.7 0.7) (thickness 0.15)) (justify left bottom mirror))
    )
    (fp_text user "License: Apache-2.0" (at -1.9 -5.75 270) (layer "B.Fab") hide
      (effects (font (size 0.7 0.7) (thickness 0.15)) (justify left bottom mirror))
    )
    (fp_text user "Author: Antmicro" (at -1.9 -4.4 270) (layer "B.Fab") hide
      (effects (font (size 0.7 0.7) (thickness 0.15)) (justify left bottom mirror))
    )
    (fp_text user "${REFERENCE}" (at -1.9 -3.1 270) (layer "B.Fab") hide
      (effects (font (size 0.7 0.7) (thickness 0.15)) (justify left bottom mirror))
    )
    (fp_line (start -0.32 -0.699) (end 0.28 -0.699) (layer "B.SilkS") (width 0.15))
    (fp_line (start -0.3 0.701) (end 0.298 0.701) (layer "B.SilkS") (width 0.15))
    (fp_rect (start -1.75 0.85) (end 1.75 -0.85) (layer "B.CrtYd") (width 0.05) (fill none))
    (fp_line (start -0.951 0.682) (end 0.949 0.682) (layer "B.Fab") (width 0.15))
    (fp_line (start -0.951 -0.68) (end 0.949 -0.68) (layer "B.Fab") (width 0.15))
    (fp_line (start -0.951 0.677) (end -0.951 -0.675) (layer "B.Fab") (width 0.15))
    (fp_line (start 0.949 0.677) (end 0.949 -0.675) (layer "B.Fab") (width 0.15))
    (pad "1" smd roundrect (at -1.1 0.001 90) (size 1 1.4) (layers "B.Cu" "B.Paste" "B.Mask") (roundrect_rratio 0.15)
      (net 379 "Net-(D29-Pad2)") (pintype "passive"))
    (pad "2" smd roundrect (at 1.1 0.001 90) (size 1 1.4) (layers "B.Cu" "B.Paste" "B.Mask") (roundrect_rratio 0.15)
      (net 135 "/PoE/VSS_POE") (pintype "passive"))
  )
)
